(kicad_pcb
	(version 20260206)
	(generator "pcbnew")
	(generator_version "10.0")
	(general
		(thickness 1.6)
		(legacy_teardrops no)
	)
	(paper "A4")
	(title_block
		(title "Bryce Canyon_IOM_IOC_16318-2_OCP.brd")
		(comment 1 "Bryce Canyon / footprints 1027-1033 of 1605")
	)
	(layers
		(0 "F.Cu" signal "TOP")
		(4 "In1.Cu" signal "L2GND")
		(6 "In2.Cu" signal "L3")
		(8 "In3.Cu" signal "L4VCC")
		(10 "In4.Cu" signal "L5VCC")
		(12 "In5.Cu" signal "L6")
		(14 "In6.Cu" signal "L7GND")
		(2 "B.Cu" signal "BOTTOM")
		(9 "F.Adhes" user "F.Adhesive")
		(11 "B.Adhes" user "B.Adhesive")
		(13 "F.Paste" user "Package Geometry/Pastemask Top")
		(15 "B.Paste" user "Package Geometry/Pastemask Bottom")
		(5 "F.SilkS" user "Ref Des/Silkscreen Top")
		(7 "B.SilkS" user "Ref Des/Silkscreen Bottom")
		(1 "F.Mask" user "Board Geometry/Soldermask Top")
		(3 "B.Mask" user "Board Geometry/Soldermask Bottom")
		(17 "Dwgs.User" user "User.Drawings")
		(19 "Cmts.User" user "User.Comments")
		(21 "Eco1.User" user "User.Eco1")
		(23 "Eco2.User" user "User.Eco2")
		(25 "Edge.Cuts" user "Board Geometry/Outline")
		(27 "Margin" user)
		(31 "F.CrtYd" user "Package Geometry/Place Bound Top")
		(29 "B.CrtYd" user "Package Geometry/Place Bound Bottom")
		(35 "F.Fab" user "Ref Des/Assembly Top")
		(33 "B.Fab" user "Ref Des/Assembly Bottom")
	)
	(footprint ""
		(layer "B.Cu")
		(at 78.2066 -130.175)
		(property "Reference" "C502"
			(at 0 0 0)
			(layer "B.SilkS")
			(hide yes)
			(effects
				(font
					(size 1.27 1.27)
				)
				(justify mirror)
			)
		)
		(property "Value" "SCD1U16V2KX-3GP"
			(at -1.1811 -2.7051 0)
			(unlocked yes)
			(layer "B.Fab")
			(hide yes)
			(effects
				(font
					(size 1.016 1.016)
					(thickness 0.1524)
				)
				(justify mirror)
			)
		)
		(property "Device Type" "C402H22"
			(at -1.1811 -4.2291 0)
			(unlocked yes)
			(layer "B.Fab")
			(hide yes)
			(effects
				(font
					(size 1.016 1.016)
					(thickness 0.1524)
				)
				(justify mirror)
			)
		)
		(duplicate_pad_numbers_are_jumpers no)
		(fp_rect
			(start 0.4318 0.9525)
			(end -0.4318 -0.9525)
			(stroke
				(width 0)
				(type default)
			)
			(fill no)
			(layer "B.CrtYd")
		)
		(fp_rect
			(start 0.4318 0.9525)
			(end -0.4318 -0.9525)
			(stroke
				(width 0)
				(type default)
			)
			(fill no)
			(layer "B.Fab")
		)
		(pad "1" smd custom
			(at 0 -0.4445 180)
			(size 0.1524 0.1524)
			(layers "B.Cu" "B.Mask" "B.Paste")
			(net "P3V3_STBY")
			(options
				(clearance outline)
				(anchor circle)
			)
			(primitives
				(gr_poly
					(pts
						(arc
							(start 0.3048 0.2032)
							(mid 0.275042 0.275042)
							(end 0.2032 0.3048)
						)
						(arc
							(start -0.2032 0.3048)
							(mid -0.275042 0.275042)
							(end -0.3048 0.2032)
						)
						(arc
							(start -0.3048 -0.2032)
							(mid -0.275042 -0.275042)
							(end -0.2032 -0.3048)
						)
						(arc
							(start 0.2032 -0.3048)
							(mid 0.275042 -0.275042)
							(end 0.3048 -0.2032)
						)
					)
					(width 0)
					(fill yes)
				)
			)
		)
		(pad "2" smd custom
			(at 0 0.4445 180)
			(size 0.1524 0.1524)
			(layers "B.Cu" "B.Mask" "B.Paste")
			(net "GND")
			(options
				(clearance outline)
				(anchor circle)
			)
			(primitives
				(gr_poly
					(pts
						(arc
							(start 0.3048 0.2032)
							(mid 0.275042 0.275042)
							(end 0.2032 0.3048)
						)
						(arc
							(start -0.2032 0.3048)
							(mid -0.275042 0.275042)
							(end -0.3048 0.2032)
						)
						(arc
							(start -0.3048 -0.2032)
							(mid -0.275042 -0.275042)
							(end -0.2032 -0.3048)
						)
						(arc
							(start 0.2032 -0.3048)
							(mid 0.275042 -0.275042)
							(end 0.3048 -0.2032)
						)
					)
					(width 0)
					(fill yes)
				)
			)
		)
	)
	(footprint ""
		(layer "B.Cu")
		(at 208.7372 -63.0428 -90)
		(property "Reference" "R589"
			(at 0 0 90)
			(layer "B.SilkS")
			(hide yes)
			(effects
				(font
					(size 1.27 1.27)
				)
				(justify mirror)
			)
		)
		(property "Value" "2K2R2F-GP"
			(at -0.064008 -3.993896 270)
			(unlocked yes)
			(layer "B.Fab")
			(hide yes)
			(effects
				(font
					(size 1.016 1.016)
					(thickness 0.1524)
				)
				(justify mirror)
			)
		)
		(property "Device Type" "R402H16"
			(at -0.064008 -5.517896 270)
			(unlocked yes)
			(layer "B.Fab")
			(hide yes)
			(effects
				(font
					(size 1.016 1.016)
					(thickness 0.1524)
				)
				(justify mirror)
			)
		)
		(duplicate_pad_numbers_are_jumpers no)
		(fp_line
			(start -0.508 -0.9398)
			(end 0.508 -0.9398)
			(stroke
				(width 0.1524)
				(type default)
			)
			(layer "B.SilkS")
		)
		(fp_line
			(start 0.508 -0.9398)
			(end 0.508 0.9398)
			(stroke
				(width 0.1524)
				(type default)
			)
			(layer "B.SilkS")
		)
		(fp_rect
			(start 0.508 0.9398)
			(end -0.508 -0.9398)
			(stroke
				(width 0)
				(type default)
			)
			(fill no)
			(layer "B.CrtYd")
		)
		(fp_rect
			(start 0.508 0.9398)
			(end -0.508 -0.9398)
			(stroke
				(width 0)
				(type default)
			)
			(fill no)
			(layer "B.Fab")
		)
		(pad "1" smd custom
			(at 0 -0.4445 90)
			(size 0.1397 0.1397)
			(layers "B.Cu" "B.Mask" "B.Paste")
			(net "P1V8")
			(options
				(clearance outline)
				(anchor circle)
			)
			(primitives
				(gr_poly
					(pts
						(arc
							(start -0.1778 0.2794)
							(mid -0.249642 0.249642)
							(end -0.2794 0.1778)
						)
						(arc
							(start -0.2794 -0.1778)
							(mid -0.249642 -0.249642)
							(end -0.1778 -0.2794)
						)
						(arc
							(start 0.1778 -0.2794)
							(mid 0.249642 -0.249642)
							(end 0.2794 -0.1778)
						)
						(arc
							(start 0.2794 0.1778)
							(mid 0.249642 0.249642)
							(end 0.1778 0.2794)
						)
					)
					(width 0)
					(fill yes)
				)
			)
		)
		(pad "2" smd custom
			(at 0 0.4445 90)
			(size 0.1397 0.1397)
			(layers "B.Cu" "B.Mask" "B.Paste")
			(net "SIO_DIN_0")
			(options
				(clearance outline)
				(anchor circle)
			)
			(primitives
				(gr_poly
					(pts
						(arc
							(start -0.1778 0.2794)
							(mid -0.249642 0.249642)
							(end -0.2794 0.1778)
						)
						(arc
							(start -0.2794 -0.1778)
							(mid -0.249642 -0.249642)
							(end -0.1778 -0.2794)
						)
						(arc
							(start 0.1778 -0.2794)
							(mid 0.249642 -0.249642)
							(end 0.2794 -0.1778)
						)
						(arc
							(start 0.2794 0.1778)
							(mid 0.249642 0.249642)
							(end 0.1778 0.2794)
						)
					)
					(width 0)
					(fill yes)
				)
			)
		)
	)
	(footprint ""
		(layer "B.Cu")
		(at 50.59426 -155.3718 -90)
		(property "Reference" "R191"
			(at 0 0 90)
			(layer "B.SilkS")
			(hide yes)
			(effects
				(font
					(size 1.27 1.27)
				)
				(justify mirror)
			)
		)
		(property "Value" "2K2R2F-GP"
			(at -0.064008 -3.993896 270)
			(unlocked yes)
			(layer "B.Fab")
			(hide yes)
			(effects
				(font
					(size 1.016 1.016)
					(thickness 0.1524)
				)
				(justify mirror)
			)
		)
		(property "Device Type" "R402H16"
			(at -0.064008 -5.517896 270)
			(unlocked yes)
			(layer "B.Fab")
			(hide yes)
			(effects
				(font
					(size 1.016 1.016)
					(thickness 0.1524)
				)
				(justify mirror)
			)
		)
		(duplicate_pad_numbers_are_jumpers no)
		(fp_line
			(start -0.508 -0.9398)
			(end 0.508 -0.9398)
			(stroke
				(width 0.1524)
				(type default)
			)
			(layer "B.SilkS")
		)
		(fp_line
			(start 0.508 -0.9398)
			(end 0.508 0.9398)
			(stroke
				(width 0.1524)
				(type default)
			)
			(layer "B.SilkS")
		)
		(fp_rect
			(start 0.508 0.9398)
			(end -0.508 -0.9398)
			(stroke
				(width 0)
				(type default)
			)
			(fill no)
			(layer "B.CrtYd")
		)
		(fp_rect
			(start 0.508 0.9398)
			(end -0.508 -0.9398)
			(stroke
				(width 0)
				(type default)
			)
			(fill no)
			(layer "B.Fab")
		)
		(pad "1" smd custom
			(at 0 -0.4445 90)
			(size 0.1397 0.1397)
			(layers "B.Cu" "B.Mask" "B.Paste")
			(net "I2C_MEZZ_OOB_SCL")
			(options
				(clearance outline)
				(anchor circle)
			)
			(primitives
				(gr_poly
					(pts
						(arc
							(start -0.1778 0.2794)
							(mid -0.249642 0.249642)
							(end -0.2794 0.1778)
						)
						(arc
							(start -0.2794 -0.1778)
							(mid -0.249642 -0.249642)
							(end -0.1778 -0.2794)
						)
						(arc
							(start 0.1778 -0.2794)
							(mid 0.249642 -0.249642)
							(end 0.2794 -0.1778)
						)
						(arc
							(start 0.2794 0.1778)
							(mid 0.249642 0.249642)
							(end 0.1778 0.2794)
						)
					)
					(width 0)
					(fill yes)
				)
			)
		)
		(pad "2" smd custom
			(at 0 0.4445 90)
			(size 0.1397 0.1397)
			(layers "B.Cu" "B.Mask" "B.Paste")
			(net "P3V3_STBY")
			(options
				(clearance outline)
				(anchor circle)
			)
			(primitives
				(gr_poly
					(pts
						(arc
							(start -0.1778 0.2794)
							(mid -0.249642 0.249642)
							(end -0.2794 0.1778)
						)
						(arc
							(start -0.2794 -0.1778)
							(mid -0.249642 -0.249642)
							(end -0.1778 -0.2794)
						)
						(arc
							(start 0.1778 -0.2794)
							(mid 0.249642 -0.249642)
							(end 0.2794 -0.1778)
						)
						(arc
							(start 0.2794 0.1778)
							(mid 0.249642 0.249642)
							(end 0.1778 0.2794)
						)
					)
					(width 0)
					(fill yes)
				)
			)
		)
	)
	(footprint ""
		(layer "B.Cu")
		(at 41.1988 -154.11704 90)
		(property "Reference" "R326"
			(at 0 0 90)
			(layer "B.SilkS")
			(hide yes)
			(effects
				(font
					(size 1.27 1.27)
				)
				(justify mirror)
			)
		)
		(property "Value" "0R2J-2-GP"
			(at -0.064008 -3.993896 90)
			(unlocked yes)
			(layer "B.Fab")
			(hide yes)
			(effects
				(font
					(size 1.016 1.016)
					(thickness 0.1524)
				)
				(justify mirror)
			)
		)
		(property "Device Type" "R402H16"
			(at -0.064008 -5.517896 90)
			(unlocked yes)
			(layer "B.Fab")
			(hide yes)
			(effects
				(font
					(size 1.016 1.016)
					(thickness 0.1524)
				)
				(justify mirror)
			)
		)
		(duplicate_pad_numbers_are_jumpers no)
		(fp_line
			(start 0.508 -0.9398)
			(end 0.508 0.9398)
			(stroke
				(width 0.1524)
				(type default)
			)
			(layer "B.SilkS")
		)
		(fp_line
			(start -0.508 -0.9398)
			(end 0.508 -0.9398)
			(stroke
				(width 0.1524)
				(type default)
			)
			(layer "B.SilkS")
		)
		(fp_rect
			(start 0.508 0.9398)
			(end -0.508 -0.9398)
			(stroke
				(width 0)
				(type default)
			)
			(fill no)
			(layer "B.CrtYd")
		)
		(fp_rect
			(start 0.508 0.9398)
			(end -0.508 -0.9398)
			(stroke
				(width 0)
				(type default)
			)
			(fill no)
			(layer "B.Fab")
		)
		(pad "1" smd custom
			(at 0 -0.4445 270)
			(size 0.1397 0.1397)
			(layers "B.Cu" "B.Mask" "B.Paste")
			(net "BMC_LOC_HB")
			(options
				(clearance outline)
				(anchor circle)
			)
			(primitives
				(gr_poly
					(pts
						(arc
							(start -0.1778 0.2794)
							(mid -0.249642 0.249642)
							(end -0.2794 0.1778)
						)
						(arc
							(start -0.2794 -0.1778)
							(mid -0.249642 -0.249642)
							(end -0.1778 -0.2794)
						)
						(arc
							(start 0.1778 -0.2794)
							(mid 0.249642 -0.249642)
							(end 0.2794 -0.1778)
						)
						(arc
							(start 0.2794 0.1778)
							(mid 0.249642 0.249642)
							(end 0.1778 0.2794)
						)
					)
					(width 0)
					(fill yes)
				)
			)
		)
		(pad "2" smd custom
			(at 0 0.4445 270)
			(size 0.1397 0.1397)
			(layers "B.Cu" "B.Mask" "B.Paste")
			(net "BMC_LOC_HEARTBEAT")
			(options
				(clearance outline)
				(anchor circle)
			)
			(primitives
				(gr_poly
					(pts
						(arc
							(start -0.1778 0.2794)
							(mid -0.249642 0.249642)
							(end -0.2794 0.1778)
						)
						(arc
							(start -0.2794 -0.1778)
							(mid -0.249642 -0.249642)
							(end -0.1778 -0.2794)
						)
						(arc
							(start 0.1778 -0.2794)
							(mid 0.249642 -0.249642)
							(end 0.2794 -0.1778)
						)
						(arc
							(start 0.2794 0.1778)
							(mid 0.249642 0.249642)
							(end 0.1778 0.2794)
						)
					)
					(width 0)
					(fill yes)
				)
			)
		)
	)
	(footprint ""
		(layer "B.Cu")
		(at 57.937908 -134.910068)
		(property "Reference" "R169"
			(at 0 0 0)
			(layer "B.SilkS")
			(hide yes)
			(effects
				(font
					(size 1.27 1.27)
				)
				(justify mirror)
			)
		)
		(property "Value" "0R2J-2-GP"
			(at -0.064008 -3.993896 0)
			(unlocked yes)
			(layer "B.Fab")
			(hide yes)
			(effects
				(font
					(size 1.016 1.016)
					(thickness 0.1524)
				)
				(justify mirror)
			)
		)
		(property "Device Type" "R402H16"
			(at -0.064008 -5.517896 0)
			(unlocked yes)
			(layer "B.Fab")
			(hide yes)
			(effects
				(font
					(size 1.016 1.016)
					(thickness 0.1524)
				)
				(justify mirror)
			)
		)
		(duplicate_pad_numbers_are_jumpers no)
		(fp_line
			(start -0.508 -0.9398)
			(end 0.508 -0.9398)
			(stroke
				(width 0.1524)
				(type default)
			)
			(layer "B.SilkS")
		)
		(fp_line
			(start 0.508 -0.9398)
			(end 0.508 0.9398)
			(stroke
				(width 0.1524)
				(type default)
			)
			(layer "B.SilkS")
		)
		(fp_rect
			(start 0.508 0.9398)
			(end -0.508 -0.9398)
			(stroke
				(width 0)
				(type default)
			)
			(fill no)
			(layer "B.CrtYd")
		)
		(fp_rect
			(start 0.508 0.9398)
			(end -0.508 -0.9398)
			(stroke
				(width 0)
				(type default)
			)
			(fill no)
			(layer "B.Fab")
		)
		(pad "1" smd custom
			(at 0 -0.4445 180)
			(size 0.1397 0.1397)
			(layers "B.Cu" "B.Mask" "B.Paste")
			(net "COMP_PWR_BTN_R_N")
			(options
				(clearance outline)
				(anchor circle)
			)
			(primitives
				(gr_poly
					(pts
						(arc
							(start -0.1778 0.2794)
							(mid -0.249642 0.249642)
							(end -0.2794 0.1778)
						)
						(arc
							(start -0.2794 -0.1778)
							(mid -0.249642 -0.249642)
							(end -0.1778 -0.2794)
						)
						(arc
							(start 0.1778 -0.2794)
							(mid 0.249642 -0.249642)
							(end 0.2794 -0.1778)
						)
						(arc
							(start 0.2794 0.1778)
							(mid 0.249642 0.249642)
							(end 0.1778 0.2794)
						)
					)
					(width 0)
					(fill yes)
				)
			)
		)
		(pad "2" smd custom
			(at 0 0.4445 180)
			(size 0.1397 0.1397)
			(layers "B.Cu" "B.Mask" "B.Paste")
			(net "COMP_PWR_BTN_N")
			(options
				(clearance outline)
				(anchor circle)
			)
			(primitives
				(gr_poly
					(pts
						(arc
							(start -0.1778 0.2794)
							(mid -0.249642 0.249642)
							(end -0.2794 0.1778)
						)
						(arc
							(start -0.2794 -0.1778)
							(mid -0.249642 -0.249642)
							(end -0.1778 -0.2794)
						)
						(arc
							(start 0.1778 -0.2794)
							(mid 0.249642 -0.249642)
							(end 0.2794 -0.1778)
						)
						(arc
							(start 0.2794 0.1778)
							(mid 0.249642 0.249642)
							(end 0.1778 0.2794)
						)
					)
					(width 0)
					(fill yes)
				)
			)
		)
	)
	(footprint ""
		(layer "B.Cu")
		(at 211.836 -89.662 -90)
		(property "Reference" "R684"
			(at 0 0 90)
			(layer "B.SilkS")
			(hide yes)
			(effects
				(font
					(size 1.27 1.27)
				)
				(justify mirror)
			)
		)
		(property "Value" "10R2F-L-GP"
			(at -0.064008 -3.993896 270)
			(unlocked yes)
			(layer "B.Fab")
			(hide yes)
			(effects
				(font
					(size 1.016 1.016)
					(thickness 0.1524)
				)
				(justify mirror)
			)
		)
		(property "Device Type" "R402H14"
			(at -0.064008 -5.517896 270)
			(unlocked yes)
			(layer "B.Fab")
			(hide yes)
			(effects
				(font
					(size 1.016 1.016)
					(thickness 0.1524)
				)
				(justify mirror)
			)
		)
		(duplicate_pad_numbers_are_jumpers no)
		(fp_line
			(start -0.508 -0.9398)
			(end 0.508 -0.9398)
			(stroke
				(width 0.1524)
				(type default)
			)
			(layer "B.SilkS")
		)
		(fp_line
			(start 0.508 -0.9398)
			(end 0.508 0.9398)
			(stroke
				(width 0.1524)
				(type default)
			)
			(layer "B.SilkS")
		)
		(fp_rect
			(start 0.508 0.9398)
			(end -0.508 -0.9398)
			(stroke
				(width 0)
				(type default)
			)
			(fill no)
			(layer "B.CrtYd")
		)
		(fp_rect
			(start 0.508 0.9398)
			(end -0.508 -0.9398)
			(stroke
				(width 0)
				(type default)
			)
			(fill no)
			(layer "B.Fab")
		)
		(pad "1" smd custom
			(at 0 -0.4445 90)
			(size 0.1397 0.1397)
			(layers "B.Cu" "B.Mask" "B.Paste")
			(net "P1V8")
			(options
				(clearance outline)
				(anchor circle)
			)
			(primitives
				(gr_poly
					(pts
						(arc
							(start -0.1778 0.2794)
							(mid -0.249642 0.249642)
							(end -0.2794 0.1778)
						)
						(arc
							(start -0.2794 -0.1778)
							(mid -0.249642 -0.249642)
							(end -0.1778 -0.2794)
						)
						(arc
							(start 0.1778 -0.2794)
							(mid 0.249642 -0.249642)
							(end 0.2794 -0.1778)
						)
						(arc
							(start 0.2794 0.1778)
							(mid 0.249642 0.249642)
							(end 0.1778 0.2794)
						)
					)
					(width 0)
					(fill yes)
				)
			)
		)
		(pad "2" smd custom
			(at 0 0.4445 90)
			(size 0.1397 0.1397)
			(layers "B.Cu" "B.Mask" "B.Paste")
			(net "SAS0_VDDH")
			(options
				(clearance outline)
				(anchor circle)
			)
			(primitives
				(gr_poly
					(pts
						(arc
							(start -0.1778 0.2794)
							(mid -0.249642 0.249642)
							(end -0.2794 0.1778)
						)
						(arc
							(start -0.2794 -0.1778)
							(mid -0.249642 -0.249642)
							(end -0.1778 -0.2794)
						)
						(arc
							(start 0.1778 -0.2794)
							(mid 0.249642 -0.249642)
							(end 0.2794 -0.1778)
						)
						(arc
							(start 0.2794 0.1778)
							(mid 0.249642 0.249642)
							(end 0.1778 0.2794)
						)
					)
					(width 0)
					(fill yes)
				)
			)
		)
	)
	(footprint ""
		(layer "B.Cu")
		(at 44.5008 -140.97)
		(property "Reference" "TP28"
			(at 0 0 0)
			(layer "B.SilkS")
			(hide yes)
			(effects
				(font
					(size 1.27 1.27)
				)
				(justify mirror)
			)
		)
		(property "Value" "TPAD28-2-GP"
			(at 0.0127 -1.6637 0)
			(unlocked yes)
			(layer "B.Fab")
			(hide yes)
			(effects
				(font
					(size 1.016 1.016)
					(thickness 0.1524)
				)
				(justify mirror)
			)
		)
		(property "Device Type" "TPAD28"
			(at 0.0127 -3.1877 0)
			(unlocked yes)
			(layer "B.Fab")
			(hide yes)
			(effects
				(font
					(size 1.016 1.016)
					(thickness 0.1524)
				)
				(justify mirror)
			)
		)
		(duplicate_pad_numbers_are_jumpers no)
		(fp_poly
			(pts
				(arc
					(start 0.3556 0)
					(mid -0.3556 0)
					(end 0.3556 0)
				)
			)
			(stroke
				(width 0)
				(type default)
			)
			(fill no)
			(layer "B.CrtYd")
		)
		(fp_poly
			(pts
				(arc
					(start 0.6096 0)
					(mid -0.6096 0)
					(end 0.6096 0)
				)
			)
			(stroke
				(width 0)
				(type default)
			)
			(fill no)
			(layer "B.Fab")
		)
		(pad "1" smd circle
			(at 0 0 180)
			(size 0.7112 0.7112)
			(layers "B.Cu" "B.Mask" "B.Paste")
			(net "TP_BMC_GPIOR2")
		)
	)
)
